# T6G (Grand Teton) — schematic netlist excerpt (pin names and nets, part order shuffled) for the footprints in the layout excerpt that follows; sources: Cadence DE-HDL packaged netlist, KiCad conversion of 04192023_DAF0TMB3IC0_F0TG_MB_C_brd_V02_OCP.brd

R6252  Q_RES  33.2 1% CHIP  pkg 0402LF  page 271 : A = SMB_LM75_0_3V3AUX_SCL ; B = SMB_HSC_TYPE_ADC_SCL
C1535  Q_CAP_DIFFBUS  DIFF BUS_0.22UF 6.3V 20% X6S  pkg C0201  page 67 : \1\ = P5E_CPU1_P3_TX_C_DP<6> ; \2\ = P5E_CPU1_P3_TX_DP<6>
PR3954  Q_RES  10K 1% CHIP  pkg 0402LF  page 147 : A = P12V_E1S_OV_FB_0 ; B = GND

(kicad_pcb
	(version 20260206)
	(generator "pcbnew")
	(generator_version "10.0")
	(general
		(thickness 1.6)
		(legacy_teardrops no)
	)
	(paper "A4")
	(title_block
		(title "04192023_DAF0TMB3IC0_F0TG_MB_C_brd_V02_OCP.brd")
		(comment 1 "Grand Teton / footprints 2942-2944 of 8354")
	)
	(layers
		(0 "F.Cu" signal "TOP")
		(4 "In1.Cu" signal "GND")
		(6 "In2.Cu" signal "IN1")
		(8 "In3.Cu" signal "GND1")
		(10 "In4.Cu" signal "IN2")
		(12 "In5.Cu" signal "GND2")
		(14 "In6.Cu" signal "IN3")
		(16 "In7.Cu" signal "GND3")
		(18 "In8.Cu" signal "VCC")
		(20 "In9.Cu" signal "VCC1")
		(22 "In10.Cu" signal "GND4")
		(24 "In11.Cu" signal "IN4")
		(26 "In12.Cu" signal "GND5")
		(28 "In13.Cu" signal "IN5")
		(30 "In14.Cu" signal "GND6")
		(32 "In15.Cu" signal "IN6")
		(34 "In16.Cu" signal "GND7")
		(2 "B.Cu" signal "BOTTOM")
		(9 "F.Adhes" user "F.Adhesive")
		(11 "B.Adhes" user "B.Adhesive")
		(13 "F.Paste" user "Package Geometry/Pastemask Top")
		(15 "B.Paste" user "Package Geometry/Pastemask Bottom")
		(5 "F.SilkS" user "Ref Des/Silkscreen Top")
		(7 "B.SilkS" user "Ref Des/Silkscreen Bottom")
		(1 "F.Mask" user "Board Geometry/Soldermask Top")
		(3 "B.Mask" user "Board Geometry/Soldermask Bottom")
		(17 "Dwgs.User" user "User.Drawings")
		(19 "Cmts.User" user "User.Comments")
		(21 "Eco1.User" user "User.Eco1")
		(23 "Eco2.User" user "User.Eco2")
		(25 "Edge.Cuts" user "Board Geometry/Outline")
		(27 "Margin" user)
		(31 "F.CrtYd" user "Package Geometry/Place Bound Top")
		(29 "B.CrtYd" user "Package Geometry/Place Bound Bottom")
		(35 "F.Fab" user "Ref Des/Assembly Top")
		(33 "B.Fab" user "Ref Des/Assembly Bottom")
	)
	(footprint ""
		(layer "F.Cu")
		(at 367.157 -411.226 -90)
		(property "Reference" "R6252"
			(at 0 0 270)
			(layer "F.SilkS")
			(hide yes)
			(effects
				(font
					(size 1.27 1.27)
				)
			)
		)
		(property "Value" ""
			(at 0 0 270)
			(layer "F.Fab")
			(effects
				(font
					(size 1.27 1.27)
				)
			)
		)
		(duplicate_pad_numbers_are_jumpers no)
		(fp_line
			(start -0.7874 0.4064)
			(end -0.7874 -0.4064)
			(stroke
				(width 0.1524)
				(type default)
			)
			(layer "F.SilkS")
		)
		(fp_line
			(start 0.7874 0.4064)
			(end -0.7874 0.4064)
			(stroke
				(width 0.1524)
				(type default)
			)
			(layer "F.SilkS")
		)
		(fp_line
			(start -0.7874 -0.4064)
			(end 0.7874 -0.4064)
			(stroke
				(width 0.1524)
				(type default)
			)
			(layer "F.SilkS")
		)
		(fp_line
			(start 0.7874 -0.4064)
			(end 0.7874 0.4064)
			(stroke
				(width 0.1524)
				(type default)
			)
			(layer "F.SilkS")
		)
		(fp_line
			(start -0.67945 0.3048)
			(end -0.67945 -0.305054)
			(stroke
				(width 0.1)
				(type default)
			)
			(layer "F.Fab")
		)
		(fp_line
			(start -0.12065 0.3048)
			(end -0.67945 0.3048)
			(stroke
				(width 0.1)
				(type default)
			)
			(layer "F.Fab")
		)
		(fp_line
			(start 0.120396 0.3048)
			(end 0.120396 0.2794)
			(stroke
				(width 0.1)
				(type default)
			)
			(layer "F.Fab")
		)
		(fp_line
			(start 0.67945 0.3048)
			(end 0.120396 0.3048)
			(stroke
				(width 0.1)
				(type default)
			)
			(layer "F.Fab")
		)
		(fp_line
			(start -0.12065 0.2794)
			(end -0.12065 0.3048)
			(stroke
				(width 0.1)
				(type default)
			)
			(layer "F.Fab")
		)
		(fp_line
			(start 0.120396 0.2794)
			(end -0.12065 0.2794)
			(stroke
				(width 0.1)
				(type default)
			)
			(layer "F.Fab")
		)
		(fp_line
			(start -0.12065 -0.2794)
			(end 0.12065 -0.2794)
			(stroke
				(width 0.1)
				(type default)
			)
			(layer "F.Fab")
		)
		(fp_line
			(start 0.12065 -0.2794)
			(end 0.12065 -0.3048)
			(stroke
				(width 0.1)
				(type default)
			)
			(layer "F.Fab")
		)
		(fp_line
			(start 0.12065 -0.3048)
			(end 0.67945 -0.3048)
			(stroke
				(width 0.1)
				(type default)
			)
			(layer "F.Fab")
		)
		(fp_line
			(start 0.67945 -0.3048)
			(end 0.67945 0.3048)
			(stroke
				(width 0.1)
				(type default)
			)
			(layer "F.Fab")
		)
		(fp_line
			(start -0.67945 -0.305054)
			(end -0.12065 -0.305054)
			(stroke
				(width 0.1)
				(type default)
			)
			(layer "F.Fab")
		)
		(fp_line
			(start -0.12065 -0.305054)
			(end -0.12065 -0.2794)
			(stroke
				(width 0.1)
				(type default)
			)
			(layer "F.Fab")
		)
		(pad "1" smd circle
			(at -0.40005 0 270)
			(size 0 0)
			(layers "F.Cu" "F.Mask" "F.Paste")
			(net "SMB_LM75_0_3V3AUX_SCL")
		)
		(pad "2" smd circle
			(at 0.40005 0 270)
			(size 0 0)
			(layers "F.Cu" "F.Mask" "F.Paste")
			(net "SMB_HSC_TYPE_ADC_SCL")
		)
	)
	(footprint ""
		(layer "F.Cu")
		(at 118.598696 -370.57203 -90)
		(property "Reference" "C1535"
			(at 0 0 270)
			(layer "F.SilkS")
			(hide yes)
			(effects
				(font
					(size 1.27 1.27)
				)
			)
		)
		(property "Value" ""
			(at 0 0 270)
			(layer "F.Fab")
			(effects
				(font
					(size 1.27 1.27)
				)
			)
		)
		(duplicate_pad_numbers_are_jumpers no)
		(fp_line
			(start -0.299974 0.150114)
			(end -0.299974 -0.150114)
			(stroke
				(width 0.1)
				(type default)
			)
			(layer "F.Fab")
		)
		(fp_line
			(start 0.299974 0.150114)
			(end -0.299974 0.150114)
			(stroke
				(width 0.1)
				(type default)
			)
			(layer "F.Fab")
		)
		(fp_line
			(start -0.299974 -0.150114)
			(end 0.299974 -0.150114)
			(stroke
				(width 0.1)
				(type default)
			)
			(layer "F.Fab")
		)
		(fp_line
			(start 0.299974 -0.150114)
			(end 0.299974 0.150114)
			(stroke
				(width 0.1)
				(type default)
			)
			(layer "F.Fab")
		)
		(pad "1" smd rect
			(at -0.2667 0 270)
			(size 0.3048 0.381)
			(layers "F.Cu" "F.Mask" "F.Paste")
			(net "P5E_CPU1_P3_TX_C_DP<6>")
		)
		(pad "2" smd rect
			(at 0.2667 0 270)
			(size 0.3048 0.381)
			(layers "F.Cu" "F.Mask" "F.Paste")
			(net "P5E_CPU1_P3_TX_DP<6>")
		)
	)
	(footprint ""
		(layer "F.Cu")
		(at 252.961648 -55.177182 180)
		(property "Reference" "PR3954"
			(at 0 0 180)
			(layer "F.SilkS")
			(hide yes)
			(effects
				(font
					(size 1.27 1.27)
				)
			)
		)
		(property "Value" ""
			(at 0 0 180)
			(layer "F.Fab")
			(effects
				(font
					(size 1.27 1.27)
				)
			)
		)
		(duplicate_pad_numbers_are_jumpers no)
		(fp_line
			(start 0.7874 0.4064)
			(end -0.7874 0.4064)
			(stroke
				(width 0.1524)
				(type default)
			)
			(layer "F.SilkS")
		)
		(fp_line
			(start 0.7874 -0.4064)
			(end 0.7874 0.4064)
			(stroke
				(width 0.1524)
				(type default)
			)
			(layer "F.SilkS")
		)
		(fp_line
			(start -0.7874 0.4064)
			(end -0.7874 -0.4064)
			(stroke
				(width 0.1524)
				(type default)
			)
			(layer "F.SilkS")
		)
		(fp_line
			(start -0.7874 -0.4064)
			(end 0.7874 -0.4064)
			(stroke
				(width 0.1524)
				(type default)
			)
			(layer "F.SilkS")
		)
		(fp_line
			(start 0.67945 0.3048)
			(end 0.120396 0.3048)
			(stroke
				(width 0.1)
				(type default)
			)
			(layer "F.Fab")
		)
		(fp_line
			(start 0.67945 -0.3048)
			(end 0.67945 0.3048)
			(stroke
				(width 0.1)
				(type default)
			)
			(layer "F.Fab")
		)
		(fp_line
			(start 0.12065 -0.2794)
			(end 0.12065 -0.3048)
			(stroke
				(width 0.1)
				(type default)
			)
			(layer "F.Fab")
		)
		(fp_line
			(start 0.12065 -0.3048)
			(end 0.67945 -0.3048)
			(stroke
				(width 0.1)
				(type default)
			)
			(layer "F.Fab")
		)
		(fp_line
			(start 0.120396 0.3048)
			(end 0.120396 0.2794)
			(stroke
				(width 0.1)
				(type default)
			)
			(layer "F.Fab")
		)
		(fp_line
			(start 0.120396 0.2794)
			(end -0.12065 0.2794)
			(stroke
				(width 0.1)
				(type default)
			)
			(layer "F.Fab")
		)
		(fp_line
			(start -0.12065 0.3048)
			(end -0.67945 0.3048)
			(stroke
				(width 0.1)
				(type default)
			)
			(layer "F.Fab")
		)
		(fp_line
			(start -0.12065 0.2794)
			(end -0.12065 0.3048)
			(stroke
				(width 0.1)
				(type default)
			)
			(layer "F.Fab")
		)
		(fp_line
			(start -0.12065 -0.2794)
			(end 0.12065 -0.2794)
			(stroke
				(width 0.1)
				(type default)
			)
			(layer "F.Fab")
		)
		(fp_line
			(start -0.12065 -0.305054)
			(end -0.12065 -0.2794)
			(stroke
				(width 0.1)
				(type default)
			)
			(layer "F.Fab")
		)
		(fp_line
			(start -0.67945 0.3048)
			(end -0.67945 -0.305054)
			(stroke
				(width 0.1)
				(type default)
			)
			(layer "F.Fab")
		)
		(fp_line
			(start -0.67945 -0.305054)
			(end -0.12065 -0.305054)
			(stroke
				(width 0.1)
				(type default)
			)
			(layer "F.Fab")
		)
		(pad "1" smd circle
			(at -0.40005 0 180)
			(size 0 0)
			(layers "F.Cu" "F.Mask" "F.Paste")
			(net "P12V_E1S_OV_FB_0")
		)
		(pad "2" smd circle
			(at 0.40005 0 180)
			(size 0 0)
			(layers "F.Cu" "F.Mask" "F.Paste")
			(net "GND")
		)
	)
)
